# T6G (Grand Teton) — schematic netlist excerpt (pin names and nets, part order shuffled) for the footprints in the layout excerpt that follows; sources: Cadence DE-HDL packaged netlist, KiCad conversion of 04192023_DAF0TMB3IC0_F0TG_MB_C_brd_V02_OCP.brd

R6852  Q_RES  0 5% CHIP  pkg 0402LF  page 81 : A = PWRGD_P0V9_RETIMER_CPU0 ; B = PWRGD_P0V9_RETIMER_CPU0_R2
C5229  Q_CAP  1UF 25V 10% EMPTY  pkg C0402  page 234 : A = P3V3_AUX ; B = GND

(kicad_pcb
	(version 20260206)
	(generator "pcbnew")
	(generator_version "10.0")
	(general
		(thickness 1.6)
		(legacy_teardrops no)
	)
	(paper "A4")
	(title_block
		(title "04192023_DAF0TMB3IC0_F0TG_MB_C_brd_V02_OCP.brd")
		(comment 1 "Grand Teton / footprints 7298-7299 of 8354")
	)
	(layers
		(0 "F.Cu" signal "TOP")
		(4 "In1.Cu" signal "GND")
		(6 "In2.Cu" signal "IN1")
		(8 "In3.Cu" signal "GND1")
		(10 "In4.Cu" signal "IN2")
		(12 "In5.Cu" signal "GND2")
		(14 "In6.Cu" signal "IN3")
		(16 "In7.Cu" signal "GND3")
		(18 "In8.Cu" signal "VCC")
		(20 "In9.Cu" signal "VCC1")
		(22 "In10.Cu" signal "GND4")
		(24 "In11.Cu" signal "IN4")
		(26 "In12.Cu" signal "GND5")
		(28 "In13.Cu" signal "IN5")
		(30 "In14.Cu" signal "GND6")
		(32 "In15.Cu" signal "IN6")
		(34 "In16.Cu" signal "GND7")
		(2 "B.Cu" signal "BOTTOM")
		(9 "F.Adhes" user "F.Adhesive")
		(11 "B.Adhes" user "B.Adhesive")
		(13 "F.Paste" user "Package Geometry/Pastemask Top")
		(15 "B.Paste" user "Package Geometry/Pastemask Bottom")
		(5 "F.SilkS" user "Ref Des/Silkscreen Top")
		(7 "B.SilkS" user "Ref Des/Silkscreen Bottom")
		(1 "F.Mask" user "Board Geometry/Soldermask Top")
		(3 "B.Mask" user "Board Geometry/Soldermask Bottom")
		(17 "Dwgs.User" user "User.Drawings")
		(19 "Cmts.User" user "User.Comments")
		(21 "Eco1.User" user "User.Eco1")
		(23 "Eco2.User" user "User.Eco2")
		(25 "Edge.Cuts" user "Board Geometry/Outline")
		(27 "Margin" user)
		(31 "F.CrtYd" user "Package Geometry/Place Bound Top")
		(29 "B.CrtYd" user "Package Geometry/Place Bound Bottom")
		(35 "F.Fab" user "Ref Des/Assembly Top")
		(33 "B.Fab" user "Ref Des/Assembly Bottom")
	)
	(footprint ""
		(layer "B.Cu")
		(at 175.133 -126.238 180)
		(property "Reference" "R6852"
			(at 0 0 0)
			(layer "B.SilkS")
			(hide yes)
			(effects
				(font
					(size 1.27 1.27)
				)
				(justify mirror)
			)
		)
		(property "Value" ""
			(at 0 0 0)
			(layer "B.Fab")
			(effects
				(font
					(size 1.27 1.27)
				)
				(justify mirror)
			)
		)
		(duplicate_pad_numbers_are_jumpers no)
		(fp_line
			(start 0.7874 0.4064)
			(end 0.7874 -0.4064)
			(stroke
				(width 0.1524)
				(type default)
			)
			(layer "B.SilkS")
		)
		(fp_line
			(start 0.7874 -0.4064)
			(end -0.7874 -0.4064)
			(stroke
				(width 0.1524)
				(type default)
			)
			(layer "B.SilkS")
		)
		(fp_line
			(start -0.7874 0.4064)
			(end 0.7874 0.4064)
			(stroke
				(width 0.1524)
				(type default)
			)
			(layer "B.SilkS")
		)
		(fp_line
			(start -0.7874 -0.4064)
			(end -0.7874 0.4064)
			(stroke
				(width 0.1524)
				(type default)
			)
			(layer "B.SilkS")
		)
		(fp_line
			(start 0.67945 0.3048)
			(end 0.67945 -0.305054)
			(stroke
				(width 0.1)
				(type default)
			)
			(layer "B.Fab")
		)
		(fp_line
			(start 0.67945 -0.305054)
			(end 0.12065 -0.305054)
			(stroke
				(width 0.1)
				(type default)
			)
			(layer "B.Fab")
		)
		(fp_line
			(start 0.12065 0.3048)
			(end 0.67945 0.3048)
			(stroke
				(width 0.1)
				(type default)
			)
			(layer "B.Fab")
		)
		(fp_line
			(start 0.12065 0.2794)
			(end 0.12065 0.3048)
			(stroke
				(width 0.1)
				(type default)
			)
			(layer "B.Fab")
		)
		(fp_line
			(start 0.12065 -0.2794)
			(end -0.12065 -0.2794)
			(stroke
				(width 0.1)
				(type default)
			)
			(layer "B.Fab")
		)
		(fp_line
			(start 0.12065 -0.305054)
			(end 0.12065 -0.2794)
			(stroke
				(width 0.1)
				(type default)
			)
			(layer "B.Fab")
		)
		(fp_line
			(start -0.120396 0.3048)
			(end -0.120396 0.2794)
			(stroke
				(width 0.1)
				(type default)
			)
			(layer "B.Fab")
		)
		(fp_line
			(start -0.120396 0.2794)
			(end 0.12065 0.2794)
			(stroke
				(width 0.1)
				(type default)
			)
			(layer "B.Fab")
		)
		(fp_line
			(start -0.12065 -0.2794)
			(end -0.12065 -0.3048)
			(stroke
				(width 0.1)
				(type default)
			)
			(layer "B.Fab")
		)
		(fp_line
			(start -0.12065 -0.3048)
			(end -0.67945 -0.3048)
			(stroke
				(width 0.1)
				(type default)
			)
			(layer "B.Fab")
		)
		(fp_line
			(start -0.67945 0.3048)
			(end -0.120396 0.3048)
			(stroke
				(width 0.1)
				(type default)
			)
			(layer "B.Fab")
		)
		(fp_line
			(start -0.67945 -0.3048)
			(end -0.67945 0.3048)
			(stroke
				(width 0.1)
				(type default)
			)
			(layer "B.Fab")
		)
		(pad "1" smd circle
			(at 0.40005 0)
			(size 0 0)
			(layers "B.Cu" "B.Mask" "B.Paste")
			(net "PWRGD_P0V9_RETIMER_CPU0")
		)
		(pad "2" smd circle
			(at -0.40005 0)
			(size 0 0)
			(layers "B.Cu" "B.Mask" "B.Paste")
			(net "PWRGD_P0V9_RETIMER_CPU0_R2")
		)
	)
	(footprint ""
		(layer "B.Cu")
		(at 14.407388 -111.004604 90)
		(property "Reference" "C5229"
			(at 0 0 90)
			(layer "B.SilkS")
			(hide yes)
			(effects
				(font
					(size 1.27 1.27)
				)
				(justify mirror)
			)
		)
		(property "Value" ""
			(at 0 0 90)
			(layer "B.Fab")
			(effects
				(font
					(size 1.27 1.27)
				)
				(justify mirror)
			)
		)
		(duplicate_pad_numbers_are_jumpers no)
		(fp_line
			(start 0.7874 -0.4064)
			(end -0.7874 -0.4064)
			(stroke
				(width 0.1524)
				(type default)
			)
			(layer "B.SilkS")
		)
		(fp_line
			(start -0.7874 -0.4064)
			(end -0.7874 0.4064)
			(stroke
				(width 0.1524)
				(type default)
			)
			(layer "B.SilkS")
		)
		(fp_line
			(start 0.7874 0.4064)
			(end 0.7874 -0.4064)
			(stroke
				(width 0.1524)
				(type default)
			)
			(layer "B.SilkS")
		)
		(fp_line
			(start -0.7874 0.4064)
			(end 0.7874 0.4064)
			(stroke
				(width 0.1524)
				(type default)
			)
			(layer "B.SilkS")
		)
		(fp_line
			(start 0.67945 -0.305054)
			(end 0.12065 -0.305054)
			(stroke
				(width 0.1)
				(type default)
			)
			(layer "B.Fab")
		)
		(fp_line
			(start 0.12065 -0.305054)
			(end 0.12065 -0.2794)
			(stroke
				(width 0.1)
				(type default)
			)
			(layer "B.Fab")
		)
		(fp_line
			(start -0.12065 -0.3048)
			(end -0.67945 -0.3048)
			(stroke
				(width 0.1)
				(type default)
			)
			(layer "B.Fab")
		)
		(fp_line
			(start -0.67945 -0.3048)
			(end -0.67945 0.3048)
			(stroke
				(width 0.1)
				(type default)
			)
			(layer "B.Fab")
		)
		(fp_line
			(start 0.12065 -0.2794)
			(end -0.12065 -0.2794)
			(stroke
				(width 0.1)
				(type default)
			)
			(layer "B.Fab")
		)
		(fp_line
			(start -0.12065 -0.2794)
			(end -0.12065 -0.3048)
			(stroke
				(width 0.1)
				(type default)
			)
			(layer "B.Fab")
		)
		(fp_line
			(start 0.12065 0.2794)
			(end 0.12065 0.3048)
			(stroke
				(width 0.1)
				(type default)
			)
			(layer "B.Fab")
		)
		(fp_line
			(start -0.120396 0.2794)
			(end 0.12065 0.2794)
			(stroke
				(width 0.1)
				(type default)
			)
			(layer "B.Fab")
		)
		(fp_line
			(start 0.67945 0.3048)
			(end 0.67945 -0.305054)
			(stroke
				(width 0.1)
				(type default)
			)
			(layer "B.Fab")
		)
		(fp_line
			(start 0.12065 0.3048)
			(end 0.67945 0.3048)
			(stroke
				(width 0.1)
				(type default)
			)
			(layer "B.Fab")
		)
		(fp_line
			(start -0.120396 0.3048)
			(end -0.120396 0.2794)
			(stroke
				(width 0.1)
				(type default)
			)
			(layer "B.Fab")
		)
		(fp_line
			(start -0.67945 0.3048)
			(end -0.120396 0.3048)
			(stroke
				(width 0.1)
				(type default)
			)
			(layer "B.Fab")
		)
		(pad "1" smd circle
			(at 0.40005 0 270)
			(size 0 0)
			(layers "B.Cu" "B.Mask" "B.Paste")
			(net "P3V3_AUX")
		)
		(pad "2" smd circle
			(at -0.40005 0 270)
			(size 0 0)
			(layers "B.Cu" "B.Mask" "B.Paste")
			(net "GND")
		)
	)
)
